(kicad_pcb
	(version 20241229)
	(generator "pcbnew")
	(generator_version "9.0")
	(general
		(thickness 1.599998)
		(legacy_teardrops no)
	)
	(paper "A4")
	(title_block
		(date "2023-02-12")
		(rev "1.1.5")
		(comment 9 "footprints 339-344 of 473")
	)
	(layers
		(0 "F.Cu" signal)
		(4 "In1.Cu" power "In1.GND")
		(6 "In2.Cu" signal)
		(8 "In3.Cu" power "In3.GND")
		(10 "In4.Cu" power "In4.VCC")
		(12 "In5.Cu" signal)
		(14 "In6.Cu" power "In6.VCC")
		(2 "B.Cu" signal)
		(9 "F.Adhes" user "F.Adhesive")
		(11 "B.Adhes" user "B.Adhesive")
		(13 "F.Paste" user)
		(15 "B.Paste" user)
		(5 "F.SilkS" user "F.Silkscreen")
		(7 "B.SilkS" user "B.Silkscreen")
		(1 "F.Mask" user)
		(3 "B.Mask" user)
		(17 "Dwgs.User" user "User.Drawings")
		(19 "Cmts.User" user "User.Comments")
		(21 "Eco1.User" user "User.Eco1")
		(23 "Eco2.User" user "User.Eco2")
		(25 "Edge.Cuts" user)
		(27 "Margin" user)
		(31 "F.CrtYd" user "F.Courtyard")
		(29 "B.CrtYd" user "B.Courtyard")
		(35 "F.Fab" user)
		(33 "B.Fab" user)
	)
	(footprint "antmicro-footprints:C_0201"
		(layer "B.Cu")
		(at 166.661328 94.497157 -90)
		(descr "Capacitor SMD 0201")
		(tags "capacitor SMD 0201")
		(property "Reference" "C57"
			(at -2.697157 0.011328 90)
			(layer "B.SilkS")
			(effects
				(font
					(size 0.7 0.7)
					(thickness 0.15)
				)
				(justify left bottom mirror)
			)
		)
		(property "Value" "C_100n_0201"
			(at 0 -1.4 90)
			(layer "B.Fab")
			(effects
				(font
					(size 0.7 0.7)
					(thickness 0.15)
				)
				(justify left bottom mirror)
			)
		)
		(property "Description" " "
			(at 0 0 270)
			(layer "F.Fab")
			(hide yes)
			(effects
				(font
					(size 1.27 1.27)
					(thickness 0.15)
				)
			)
		)
		(property "Author" "Antmicro"
			(at 72.164171 261.158485 0)
			(layer "B.Fab")
			(hide yes)
			(effects
				(font
					(size 1 1)
					(thickness 0.15)
				)
				(justify mirror)
			)
		)
		(property "Dielectric" ""
			(at 72.164171 261.158485 0)
			(layer "B.Fab")
			(hide yes)
			(effects
				(font
					(size 1 1)
					(thickness 0.15)
				)
				(justify mirror)
			)
		)
		(property "License" "Apache-2.0"
			(at 72.164171 261.158485 0)
			(layer "B.Fab")
			(hide yes)
			(effects
				(font
					(size 1 1)
					(thickness 0.15)
				)
				(justify mirror)
			)
		)
		(property "MPN" "CC0201KRX6S5BB104"
			(at 72.164171 261.158485 0)
			(layer "B.Fab")
			(hide yes)
			(effects
				(font
					(size 1 1)
					(thickness 0.15)
				)
				(justify mirror)
			)
		)
		(property "Manufacturer" "Yaego"
			(at 72.164171 261.158485 0)
			(layer "B.Fab")
			(hide yes)
			(effects
				(font
					(size 1 1)
					(thickness 0.15)
				)
				(justify mirror)
			)
		)
		(property "Val" "100n"
			(at 72.164171 261.158485 0)
			(layer "B.Fab")
			(hide yes)
			(effects
				(font
					(size 1 1)
					(thickness 0.15)
				)
				(justify mirror)
			)
		)
		(property "Voltage" ""
			(at 72.164171 261.158485 0)
			(layer "B.Fab")
			(hide yes)
			(effects
				(font
					(size 1 1)
					(thickness 0.15)
				)
				(justify mirror)
			)
		)
		(sheetname "FPGA power")
		(sheetfile "fpga-power.kicad_sch")
		(attr smd)
		(fp_rect
			(start -0.72 0.38)
			(end 0.72 -0.38)
			(stroke
				(width 0.05)
				(type solid)
			)
			(fill no)
			(layer "B.CrtYd")
		)
		(fp_rect
			(start 0.3 -0.15)
			(end -0.301 0.149)
			(stroke
				(width 0.15)
				(type solid)
			)
			(fill no)
			(layer "B.Fab")
		)
		(pad "" smd roundrect
			(at -0.349 0.002 270)
			(size 0.318 0.36)
			(layers "B.Paste")
			(roundrect_rratio 0.25)
		)
		(pad "" smd roundrect
			(at 0.341 0.002 270)
			(size 0.318 0.36)
			(layers "B.Paste")
			(roundrect_rratio 0.25)
		)
		(pad "1" smd roundrect
			(at -0.321 0.002 270)
			(size 0.46 0.4)
			(layers "B.Cu" "B.Mask")
			(roundrect_rratio 0.25)
			(net 460 "1V8_SYS")
			(pintype "passive")
		)
		(pad "2" smd roundrect
			(at 0.32 0.002 270)
			(size 0.46 0.4)
			(layers "B.Cu" "B.Mask")
			(roundrect_rratio 0.25)
			(net 5 "GND")
			(pintype "passive")
		)
	)
	(footprint "antmicro-footprints:C_0201"
		(layer "B.Cu")
		(at 167.736328 97.997157 90)
		(descr "Capacitor SMD 0201")
		(tags "capacitor SMD 0201")
		(property "Reference" "C90"
			(at 0.847157 -0.286328 270)
			(layer "B.SilkS")
			(effects
				(font
					(size 0.7 0.7)
					(thickness 0.15)
				)
				(justify left bottom mirror)
			)
		)
		(property "Value" "C_100n_0201"
			(at 0 -1.4 270)
			(layer "B.Fab")
			(effects
				(font
					(size 0.7 0.7)
					(thickness 0.15)
				)
				(justify left bottom mirror)
			)
		)
		(property "Description" " "
			(at 0 0 90)
			(layer "F.Fab")
			(hide yes)
			(effects
				(font
					(size 1.27 1.27)
					(thickness 0.15)
				)
			)
		)
		(property "Author" "Antmicro"
			(at 265.733485 -69.739171 0)
			(layer "B.Fab")
			(hide yes)
			(effects
				(font
					(size 1 1)
					(thickness 0.15)
				)
				(justify mirror)
			)
		)
		(property "Dielectric" ""
			(at 265.733485 -69.739171 0)
			(layer "B.Fab")
			(hide yes)
			(effects
				(font
					(size 1 1)
					(thickness 0.15)
				)
				(justify mirror)
			)
		)
		(property "License" "Apache-2.0"
			(at 265.733485 -69.739171 0)
			(layer "B.Fab")
			(hide yes)
			(effects
				(font
					(size 1 1)
					(thickness 0.15)
				)
				(justify mirror)
			)
		)
		(property "MPN" "CC0201KRX6S5BB104"
			(at 265.733485 -69.739171 0)
			(layer "B.Fab")
			(hide yes)
			(effects
				(font
					(size 1 1)
					(thickness 0.15)
				)
				(justify mirror)
			)
		)
		(property "Manufacturer" "Yaego"
			(at 265.733485 -69.739171 0)
			(layer "B.Fab")
			(hide yes)
			(effects
				(font
					(size 1 1)
					(thickness 0.15)
				)
				(justify mirror)
			)
		)
		(property "Val" "100n"
			(at 265.733485 -69.739171 0)
			(layer "B.Fab")
			(hide yes)
			(effects
				(font
					(size 1 1)
					(thickness 0.15)
				)
				(justify mirror)
			)
		)
		(property "Voltage" ""
			(at 265.733485 -69.739171 0)
			(layer "B.Fab")
			(hide yes)
			(effects
				(font
					(size 1 1)
					(thickness 0.15)
				)
				(justify mirror)
			)
		)
		(sheetname "FPGA power")
		(sheetfile "fpga-power.kicad_sch")
		(attr smd)
		(fp_rect
			(start -0.72 0.38)
			(end 0.72 -0.38)
			(stroke
				(width 0.05)
				(type solid)
			)
			(fill no)
			(layer "B.CrtYd")
		)
		(fp_rect
			(start 0.3 -0.15)
			(end -0.301 0.149)
			(stroke
				(width 0.15)
				(type solid)
			)
			(fill no)
			(layer "B.Fab")
		)
		(pad "" smd roundrect
			(at -0.349 0.002 90)
			(size 0.318 0.36)
			(layers "B.Paste")
			(roundrect_rratio 0.25)
		)
		(pad "" smd roundrect
			(at 0.341 0.002 90)
			(size 0.318 0.36)
			(layers "B.Paste")
			(roundrect_rratio 0.25)
		)
		(pad "1" smd roundrect
			(at -0.321 0.002 90)
			(size 0.46 0.4)
			(layers "B.Cu" "B.Mask")
			(roundrect_rratio 0.25)
			(net 465 "1V0_SYS")
			(pintype "passive")
		)
		(pad "2" smd roundrect
			(at 0.32 0.002 90)
			(size 0.46 0.4)
			(layers "B.Cu" "B.Mask")
			(roundrect_rratio 0.25)
			(net 5 "GND")
			(pintype "passive")
		)
	)
	(footprint "antmicro-footprints:C_0201"
		(layer "B.Cu")
		(at 165.036328 91.375 180)
		(descr "Capacitor SMD 0201")
		(tags "capacitor SMD 0201")
		(property "Reference" "C60"
			(at 0.536328 -0.325 0)
			(layer "B.SilkS")
			(effects
				(font
					(size 0.7 0.7)
					(thickness 0.15)
				)
				(justify left bottom mirror)
			)
		)
		(property "Value" "C_100n_0201"
			(at 0 -1.4 0)
			(layer "B.Fab")
			(effects
				(font
					(size 0.7 0.7)
					(thickness 0.15)
				)
				(justify left bottom mirror)
			)
		)
		(property "Description" " "
			(at 0 0 180)
			(layer "F.Fab")
			(hide yes)
			(effects
				(font
					(size 1.27 1.27)
					(thickness 0.15)
				)
			)
		)
		(property "Author" "Antmicro"
			(at 330.072656 182.75 0)
			(layer "B.Fab")
			(hide yes)
			(effects
				(font
					(size 1 1)
					(thickness 0.15)
				)
				(justify mirror)
			)
		)
		(property "Dielectric" ""
			(at 330.072656 182.75 0)
			(layer "B.Fab")
			(hide yes)
			(effects
				(font
					(size 1 1)
					(thickness 0.15)
				)
				(justify mirror)
			)
		)
		(property "License" "Apache-2.0"
			(at 330.072656 182.75 0)
			(layer "B.Fab")
			(hide yes)
			(effects
				(font
					(size 1 1)
					(thickness 0.15)
				)
				(justify mirror)
			)
		)
		(property "MPN" "CC0201KRX6S5BB104"
			(at 330.072656 182.75 0)
			(layer "B.Fab")
			(hide yes)
			(effects
				(font
					(size 1 1)
					(thickness 0.15)
				)
				(justify mirror)
			)
		)
		(property "Manufacturer" "Yaego"
			(at 330.072656 182.75 0)
			(layer "B.Fab")
			(hide yes)
			(effects
				(font
					(size 1 1)
					(thickness 0.15)
				)
				(justify mirror)
			)
		)
		(property "Val" "100n"
			(at 330.072656 182.75 0)
			(layer "B.Fab")
			(hide yes)
			(effects
				(font
					(size 1 1)
					(thickness 0.15)
				)
				(justify mirror)
			)
		)
		(property "Voltage" ""
			(at 330.072656 182.75 0)
			(layer "B.Fab")
			(hide yes)
			(effects
				(font
					(size 1 1)
					(thickness 0.15)
				)
				(justify mirror)
			)
		)
		(sheetname "FPGA power")
		(sheetfile "fpga-power.kicad_sch")
		(attr smd)
		(fp_rect
			(start -0.72 0.38)
			(end 0.72 -0.38)
			(stroke
				(width 0.05)
				(type solid)
			)
			(fill no)
			(layer "B.CrtYd")
		)
		(fp_rect
			(start 0.3 -0.15)
			(end -0.301 0.149)
			(stroke
				(width 0.15)
				(type solid)
			)
			(fill no)
			(layer "B.Fab")
		)
		(pad "" smd roundrect
			(at -0.349 0.002 180)
			(size 0.318 0.36)
			(layers "B.Paste")
			(roundrect_rratio 0.25)
		)
		(pad "" smd roundrect
			(at 0.341 0.002 180)
			(size 0.318 0.36)
			(layers "B.Paste")
			(roundrect_rratio 0.25)
		)
		(pad "1" smd roundrect
			(at -0.321 0.002 180)
			(size 0.46 0.4)
			(layers "B.Cu" "B.Mask")
			(roundrect_rratio 0.25)
			(net 460 "1V8_SYS")
			(pintype "passive")
		)
		(pad "2" smd roundrect
			(at 0.32 0.002 180)
			(size 0.46 0.4)
			(layers "B.Cu" "B.Mask")
			(roundrect_rratio 0.25)
			(net 5 "GND")
			(pintype "passive")
		)
	)
	(footprint "antmicro-footprints:C_0201"
		(layer "B.Cu")
		(at 169.411328 97.497157 90)
		(descr "Capacitor SMD 0201")
		(tags "capacitor SMD 0201")
		(property "Reference" "C92"
			(at 0.697157 -0.311328 270)
			(layer "B.SilkS")
			(effects
				(font
					(size 0.7 0.7)
					(thickness 0.15)
				)
				(justify left bottom mirror)
			)
		)
		(property "Value" "C_100n_0201"
			(at 0 -1.4 270)
			(layer "B.Fab")
			(effects
				(font
					(size 0.7 0.7)
					(thickness 0.15)
				)
				(justify left bottom mirror)
			)
		)
		(property "Description" " "
			(at 0 0 90)
			(layer "F.Fab")
			(hide yes)
			(effects
				(font
					(size 1.27 1.27)
					(thickness 0.15)
				)
			)
		)
		(property "Author" "Antmicro"
			(at 266.908485 -71.914171 0)
			(layer "B.Fab")
			(hide yes)
			(effects
				(font
					(size 1 1)
					(thickness 0.15)
				)
				(justify mirror)
			)
		)
		(property "Dielectric" ""
			(at 266.908485 -71.914171 0)
			(layer "B.Fab")
			(hide yes)
			(effects
				(font
					(size 1 1)
					(thickness 0.15)
				)
				(justify mirror)
			)
		)
		(property "License" "Apache-2.0"
			(at 266.908485 -71.914171 0)
			(layer "B.Fab")
			(hide yes)
			(effects
				(font
					(size 1 1)
					(thickness 0.15)
				)
				(justify mirror)
			)
		)
		(property "MPN" "CC0201KRX6S5BB104"
			(at 266.908485 -71.914171 0)
			(layer "B.Fab")
			(hide yes)
			(effects
				(font
					(size 1 1)
					(thickness 0.15)
				)
				(justify mirror)
			)
		)
		(property "Manufacturer" "Yaego"
			(at 266.908485 -71.914171 0)
			(layer "B.Fab")
			(hide yes)
			(effects
				(font
					(size 1 1)
					(thickness 0.15)
				)
				(justify mirror)
			)
		)
		(property "Val" "100n"
			(at 266.908485 -71.914171 0)
			(layer "B.Fab")
			(hide yes)
			(effects
				(font
					(size 1 1)
					(thickness 0.15)
				)
				(justify mirror)
			)
		)
		(property "Voltage" ""
			(at 266.908485 -71.914171 0)
			(layer "B.Fab")
			(hide yes)
			(effects
				(font
					(size 1 1)
					(thickness 0.15)
				)
				(justify mirror)
			)
		)
		(sheetname "FPGA power")
		(sheetfile "fpga-power.kicad_sch")
		(attr smd)
		(fp_rect
			(start -0.72 0.38)
			(end 0.72 -0.38)
			(stroke
				(width 0.05)
				(type solid)
			)
			(fill no)
			(layer "B.CrtYd")
		)
		(fp_rect
			(start 0.3 -0.15)
			(end -0.301 0.149)
			(stroke
				(width 0.15)
				(type solid)
			)
			(fill no)
			(layer "B.Fab")
		)
		(pad "" smd roundrect
			(at -0.349 0.002 90)
			(size 0.318 0.36)
			(layers "B.Paste")
			(roundrect_rratio 0.25)
		)
		(pad "" smd roundrect
			(at 0.341 0.002 90)
			(size 0.318 0.36)
			(layers "B.Paste")
			(roundrect_rratio 0.25)
		)
		(pad "1" smd roundrect
			(at -0.321 0.002 90)
			(size 0.46 0.4)
			(layers "B.Cu" "B.Mask")
			(roundrect_rratio 0.25)
			(net 465 "1V0_SYS")
			(pintype "passive")
		)
		(pad "2" smd roundrect
			(at 0.32 0.002 90)
			(size 0.46 0.4)
			(layers "B.Cu" "B.Mask")
			(roundrect_rratio 0.25)
			(net 5 "GND")
			(pintype "passive")
		)
	)
	(footprint "antmicro-footprints:C_0201"
		(layer "B.Cu")
		(at 167.411328 94.497157 -90)
		(descr "Capacitor SMD 0201")
		(tags "capacitor SMD 0201")
		(property "Reference" "C63"
			(at -2.697157 -0.188672 90)
			(layer "B.SilkS")
			(effects
				(font
					(size 0.7 0.7)
					(thickness 0.15)
				)
				(justify left bottom mirror)
			)
		)
		(property "Value" "C_100n_0201"
			(at 0 -1.4 90)
			(layer "B.Fab")
			(effects
				(font
					(size 0.7 0.7)
					(thickness 0.15)
				)
				(justify left bottom mirror)
			)
		)
		(property "Description" " "
			(at 0 0 270)
			(layer "F.Fab")
			(hide yes)
			(effects
				(font
					(size 1.27 1.27)
					(thickness 0.15)
				)
			)
		)
		(property "Author" "Antmicro"
			(at 72.914171 261.908485 0)
			(layer "B.Fab")
			(hide yes)
			(effects
				(font
					(size 1 1)
					(thickness 0.15)
				)
				(justify mirror)
			)
		)
		(property "Dielectric" ""
			(at 72.914171 261.908485 0)
			(layer "B.Fab")
			(hide yes)
			(effects
				(font
					(size 1 1)
					(thickness 0.15)
				)
				(justify mirror)
			)
		)
		(property "License" "Apache-2.0"
			(at 72.914171 261.908485 0)
			(layer "B.Fab")
			(hide yes)
			(effects
				(font
					(size 1 1)
					(thickness 0.15)
				)
				(justify mirror)
			)
		)
		(property "MPN" "CC0201KRX6S5BB104"
			(at 72.914171 261.908485 0)
			(layer "B.Fab")
			(hide yes)
			(effects
				(font
					(size 1 1)
					(thickness 0.15)
				)
				(justify mirror)
			)
		)
		(property "Manufacturer" "Yaego"
			(at 72.914171 261.908485 0)
			(layer "B.Fab")
			(hide yes)
			(effects
				(font
					(size 1 1)
					(thickness 0.15)
				)
				(justify mirror)
			)
		)
		(property "Val" "100n"
			(at 72.914171 261.908485 0)
			(layer "B.Fab")
			(hide yes)
			(effects
				(font
					(size 1 1)
					(thickness 0.15)
				)
				(justify mirror)
			)
		)
		(property "Voltage" ""
			(at 72.914171 261.908485 0)
			(layer "B.Fab")
			(hide yes)
			(effects
				(font
					(size 1 1)
					(thickness 0.15)
				)
				(justify mirror)
			)
		)
		(sheetname "FPGA power")
		(sheetfile "fpga-power.kicad_sch")
		(attr smd)
		(fp_rect
			(start -0.72 0.38)
			(end 0.72 -0.38)
			(stroke
				(width 0.05)
				(type solid)
			)
			(fill no)
			(layer "B.CrtYd")
		)
		(fp_rect
			(start 0.3 -0.15)
			(end -0.301 0.149)
			(stroke
				(width 0.15)
				(type solid)
			)
			(fill no)
			(layer "B.Fab")
		)
		(pad "" smd roundrect
			(at -0.349 0.002 270)
			(size 0.318 0.36)
			(layers "B.Paste")
			(roundrect_rratio 0.25)
		)
		(pad "" smd roundrect
			(at 0.341 0.002 270)
			(size 0.318 0.36)
			(layers "B.Paste")
			(roundrect_rratio 0.25)
		)
		(pad "1" smd roundrect
			(at -0.321 0.002 270)
			(size 0.46 0.4)
			(layers "B.Cu" "B.Mask")
			(roundrect_rratio 0.25)
			(net 460 "1V8_SYS")
			(pintype "passive")
		)
		(pad "2" smd roundrect
			(at 0.32 0.002 270)
			(size 0.46 0.4)
			(layers "B.Cu" "B.Mask")
			(roundrect_rratio 0.25)
			(net 5 "GND")
			(pintype "passive")
		)
	)
	(footprint "antmicro-footprints:C_0201"
		(layer "B.Cu")
		(at 169.536328 95.697157 180)
		(descr "Capacitor SMD 0201")
		(tags "capacitor SMD 0201")
		(property "Reference" "C67"
			(at 0.736328 2.797157 90)
			(layer "B.SilkS")
			(effects
				(font
					(size 0.7 0.7)
					(thickness 0.15)
				)
				(justify left bottom mirror)
			)
		)
		(property "Value" "C_100n_0201"
			(at 0 -1.4 0)
			(layer "B.Fab")
			(effects
				(font
					(size 0.7 0.7)
					(thickness 0.15)
				)
				(justify left bottom mirror)
			)
		)
		(property "Description" " "
			(at 0 0 180)
			(layer "F.Fab")
			(hide yes)
			(effects
				(font
					(size 1.27 1.27)
					(thickness 0.15)
				)
			)
		)
		(property "Author" "Antmicro"
			(at 339.072656 191.394314 0)
			(layer "B.Fab")
			(hide yes)
			(effects
				(font
					(size 1 1)
					(thickness 0.15)
				)
				(justify mirror)
			)
		)
		(property "Dielectric" ""
			(at 339.072656 191.394314 0)
			(layer "B.Fab")
			(hide yes)
			(effects
				(font
					(size 1 1)
					(thickness 0.15)
				)
				(justify mirror)
			)
		)
		(property "License" "Apache-2.0"
			(at 339.072656 191.394314 0)
			(layer "B.Fab")
			(hide yes)
			(effects
				(font
					(size 1 1)
					(thickness 0.15)
				)
				(justify mirror)
			)
		)
		(property "MPN" "CC0201KRX6S5BB104"
			(at 339.072656 191.394314 0)
			(layer "B.Fab")
			(hide yes)
			(effects
				(font
					(size 1 1)
					(thickness 0.15)
				)
				(justify mirror)
			)
		)
		(property "Manufacturer" "Yaego"
			(at 339.072656 191.394314 0)
			(layer "B.Fab")
			(hide yes)
			(effects
				(font
					(size 1 1)
					(thickness 0.15)
				)
				(justify mirror)
			)
		)
		(property "Val" "100n"
			(at 339.072656 191.394314 0)
			(layer "B.Fab")
			(hide yes)
			(effects
				(font
					(size 1 1)
					(thickness 0.15)
				)
				(justify mirror)
			)
		)
		(property "Voltage" ""
			(at 339.072656 191.394314 0)
			(layer "B.Fab")
			(hide yes)
			(effects
				(font
					(size 1 1)
					(thickness 0.15)
				)
				(justify mirror)
			)
		)
		(sheetname "FPGA power")
		(sheetfile "fpga-power.kicad_sch")
		(attr smd)
		(fp_rect
			(start -0.72 0.38)
			(end 0.72 -0.38)
			(stroke
				(width 0.05)
				(type solid)
			)
			(fill no)
			(layer "B.CrtYd")
		)
		(fp_rect
			(start 0.3 -0.15)
			(end -0.301 0.149)
			(stroke
				(width 0.15)
				(type solid)
			)
			(fill no)
			(layer "B.Fab")
		)
		(pad "" smd roundrect
			(at -0.349 0.002 180)
			(size 0.318 0.36)
			(layers "B.Paste")
			(roundrect_rratio 0.25)
		)
		(pad "" smd roundrect
			(at 0.341 0.002 180)
			(size 0.318 0.36)
			(layers "B.Paste")
			(roundrect_rratio 0.25)
		)
		(pad "1" smd roundrect
			(at -0.321 0.002 180)
			(size 0.46 0.4)
			(layers "B.Cu" "B.Mask")
			(roundrect_rratio 0.25)
			(net 460 "1V8_SYS")
			(pintype "passive")
		)
		(pad "2" smd roundrect
			(at 0.32 0.002 180)
			(size 0.46 0.4)
			(layers "B.Cu" "B.Mask")
			(roundrect_rratio 0.25)
			(net 5 "GND")
			(pintype "passive")
		)
	)
)
